(kicad_pcb
	(version 20260206)
	(generator "pcbnew")
	(generator_version "10.0")
	(general
		(thickness 1.6)
		(legacy_teardrops no)
	)
	(paper "A4")
	(title_block
		(title "03242023_DA0F0TMBIJ0_F0T_Motherboard_J_brd_V01_OCP.brd")
		(comment 1 "Grand Teton / footprints 1393-1399 of 6105")
	)
	(layers
		(0 "F.Cu" signal "TOP")
		(4 "In1.Cu" signal "GND")
		(6 "In2.Cu" signal "IN1")
		(8 "In3.Cu" signal "GND1")
		(10 "In4.Cu" signal "IN2")
		(12 "In5.Cu" signal "GND2")
		(14 "In6.Cu" signal "IN3")
		(16 "In7.Cu" signal "GND3")
		(18 "In8.Cu" signal "VCC")
		(20 "In9.Cu" signal "VCC1")
		(22 "In10.Cu" signal "GND4")
		(24 "In11.Cu" signal "IN4")
		(26 "In12.Cu" signal "GND5")
		(28 "In13.Cu" signal "IN5")
		(30 "In14.Cu" signal "GND6")
		(32 "In15.Cu" signal "IN6")
		(34 "In16.Cu" signal "GND7")
		(2 "B.Cu" signal "BOTTOM")
		(9 "F.Adhes" user "F.Adhesive")
		(11 "B.Adhes" user "B.Adhesive")
		(13 "F.Paste" user "Package Geometry/Pastemask Top")
		(15 "B.Paste" user "Package Geometry/Pastemask Bottom")
		(5 "F.SilkS" user "Ref Des/Silkscreen Top")
		(7 "B.SilkS" user "Ref Des/Silkscreen Bottom")
		(1 "F.Mask" user "Board Geometry/Soldermask Top")
		(3 "B.Mask" user "Board Geometry/Soldermask Bottom")
		(17 "Dwgs.User" user "User.Drawings")
		(19 "Cmts.User" user "User.Comments")
		(21 "Eco1.User" user "User.Eco1")
		(23 "Eco2.User" user "User.Eco2")
		(25 "Edge.Cuts" user "Board Geometry/Outline")
		(27 "Margin" user)
		(31 "F.CrtYd" user "Package Geometry/Place Bound Top")
		(29 "B.CrtYd" user "Package Geometry/Place Bound Bottom")
		(35 "F.Fab" user "Ref Des/Assembly Top")
		(33 "B.Fab" user "Ref Des/Assembly Bottom")
	)
	(footprint ""
		(layer "F.Cu")
		(at 252.222 -37.667946 180)
		(property "Reference" "R3978"
			(at 0 0 180)
			(layer "F.SilkS")
			(hide yes)
			(effects
				(font
					(size 1.27 1.27)
				)
			)
		)
		(property "Value" ""
			(at 0 0 180)
			(layer "F.Fab")
			(effects
				(font
					(size 1.27 1.27)
				)
			)
		)
		(duplicate_pad_numbers_are_jumpers no)
		(fp_line
			(start 0.7874 0.4064)
			(end -0.7874 0.4064)
			(stroke
				(width 0.1524)
				(type default)
			)
			(layer "F.SilkS")
		)
		(fp_line
			(start 0.7874 -0.4064)
			(end 0.7874 0.4064)
			(stroke
				(width 0.1524)
				(type default)
			)
			(layer "F.SilkS")
		)
		(fp_line
			(start -0.7874 0.4064)
			(end -0.7874 -0.4064)
			(stroke
				(width 0.1524)
				(type default)
			)
			(layer "F.SilkS")
		)
		(fp_line
			(start -0.7874 -0.4064)
			(end 0.7874 -0.4064)
			(stroke
				(width 0.1524)
				(type default)
			)
			(layer "F.SilkS")
		)
		(fp_line
			(start 0.67945 0.3048)
			(end 0.120396 0.3048)
			(stroke
				(width 0.1)
				(type default)
			)
			(layer "F.Fab")
		)
		(fp_line
			(start 0.67945 -0.3048)
			(end 0.67945 0.3048)
			(stroke
				(width 0.1)
				(type default)
			)
			(layer "F.Fab")
		)
		(fp_line
			(start 0.12065 -0.2794)
			(end 0.12065 -0.3048)
			(stroke
				(width 0.1)
				(type default)
			)
			(layer "F.Fab")
		)
		(fp_line
			(start 0.12065 -0.3048)
			(end 0.67945 -0.3048)
			(stroke
				(width 0.1)
				(type default)
			)
			(layer "F.Fab")
		)
		(fp_line
			(start 0.120396 0.3048)
			(end 0.120396 0.2794)
			(stroke
				(width 0.1)
				(type default)
			)
			(layer "F.Fab")
		)
		(fp_line
			(start 0.120396 0.2794)
			(end -0.12065 0.2794)
			(stroke
				(width 0.1)
				(type default)
			)
			(layer "F.Fab")
		)
		(fp_line
			(start -0.12065 0.3048)
			(end -0.67945 0.3048)
			(stroke
				(width 0.1)
				(type default)
			)
			(layer "F.Fab")
		)
		(fp_line
			(start -0.12065 0.2794)
			(end -0.12065 0.3048)
			(stroke
				(width 0.1)
				(type default)
			)
			(layer "F.Fab")
		)
		(fp_line
			(start -0.12065 -0.2794)
			(end 0.12065 -0.2794)
			(stroke
				(width 0.1)
				(type default)
			)
			(layer "F.Fab")
		)
		(fp_line
			(start -0.12065 -0.305054)
			(end -0.12065 -0.2794)
			(stroke
				(width 0.1)
				(type default)
			)
			(layer "F.Fab")
		)
		(fp_line
			(start -0.67945 0.3048)
			(end -0.67945 -0.305054)
			(stroke
				(width 0.1)
				(type default)
			)
			(layer "F.Fab")
		)
		(fp_line
			(start -0.67945 -0.305054)
			(end -0.12065 -0.305054)
			(stroke
				(width 0.1)
				(type default)
			)
			(layer "F.Fab")
		)
		(pad "1" smd circle
			(at -0.40005 0 180)
			(size 0 0)
			(layers "F.Cu" "F.Mask" "F.Paste")
			(net "P3V3_AUX")
		)
		(pad "2" smd circle
			(at 0.40005 0 180)
			(size 0 0)
			(layers "F.Cu" "F.Mask" "F.Paste")
			(net "HP_LVC3_E1S_0_HSC_PWRGD")
		)
	)
	(footprint ""
		(layer "F.Cu")
		(at 86.94039 -53.875686 90)
		(property "Reference" "PC2149"
			(at 0 0 90)
			(layer "F.SilkS")
			(hide yes)
			(effects
				(font
					(size 1.27 1.27)
				)
			)
		)
		(property "Value" ""
			(at 0 0 90)
			(layer "F.Fab")
			(effects
				(font
					(size 1.27 1.27)
				)
			)
		)
		(duplicate_pad_numbers_are_jumpers no)
		(fp_line
			(start 0.7874 -0.4064)
			(end 0.7874 0.4064)
			(stroke
				(width 0.1524)
				(type default)
			)
			(layer "F.SilkS")
		)
		(fp_line
			(start -0.7874 -0.4064)
			(end 0.7874 -0.4064)
			(stroke
				(width 0.1524)
				(type default)
			)
			(layer "F.SilkS")
		)
		(fp_line
			(start 0.7874 0.4064)
			(end -0.7874 0.4064)
			(stroke
				(width 0.1524)
				(type default)
			)
			(layer "F.SilkS")
		)
		(fp_line
			(start -0.7874 0.4064)
			(end -0.7874 -0.4064)
			(stroke
				(width 0.1524)
				(type default)
			)
			(layer "F.SilkS")
		)
		(fp_line
			(start -0.12065 -0.305054)
			(end -0.12065 -0.2794)
			(stroke
				(width 0.1)
				(type default)
			)
			(layer "F.Fab")
		)
		(fp_line
			(start -0.67945 -0.305054)
			(end -0.12065 -0.305054)
			(stroke
				(width 0.1)
				(type default)
			)
			(layer "F.Fab")
		)
		(fp_line
			(start 0.67945 -0.3048)
			(end 0.67945 0.3048)
			(stroke
				(width 0.1)
				(type default)
			)
			(layer "F.Fab")
		)
		(fp_line
			(start 0.12065 -0.3048)
			(end 0.67945 -0.3048)
			(stroke
				(width 0.1)
				(type default)
			)
			(layer "F.Fab")
		)
		(fp_line
			(start 0.12065 -0.2794)
			(end 0.12065 -0.3048)
			(stroke
				(width 0.1)
				(type default)
			)
			(layer "F.Fab")
		)
		(fp_line
			(start -0.12065 -0.2794)
			(end 0.12065 -0.2794)
			(stroke
				(width 0.1)
				(type default)
			)
			(layer "F.Fab")
		)
		(fp_line
			(start 0.120396 0.2794)
			(end -0.12065 0.2794)
			(stroke
				(width 0.1)
				(type default)
			)
			(layer "F.Fab")
		)
		(fp_line
			(start -0.12065 0.2794)
			(end -0.12065 0.3048)
			(stroke
				(width 0.1)
				(type default)
			)
			(layer "F.Fab")
		)
		(fp_line
			(start 0.67945 0.3048)
			(end 0.120396 0.3048)
			(stroke
				(width 0.1)
				(type default)
			)
			(layer "F.Fab")
		)
		(fp_line
			(start 0.120396 0.3048)
			(end 0.120396 0.2794)
			(stroke
				(width 0.1)
				(type default)
			)
			(layer "F.Fab")
		)
		(fp_line
			(start -0.12065 0.3048)
			(end -0.67945 0.3048)
			(stroke
				(width 0.1)
				(type default)
			)
			(layer "F.Fab")
		)
		(fp_line
			(start -0.67945 0.3048)
			(end -0.67945 -0.305054)
			(stroke
				(width 0.1)
				(type default)
			)
			(layer "F.Fab")
		)
		(pad "1" smd circle
			(at -0.40005 0 90)
			(size 0 0)
			(layers "F.Cu" "F.Mask" "F.Paste")
			(net "P3V3_OCP_V3_2_R")
		)
		(pad "2" smd circle
			(at 0.40005 0 90)
			(size 0 0)
			(layers "F.Cu" "F.Mask" "F.Paste")
			(net "P3V3_OCP_GATE_2")
		)
	)
	(footprint ""
		(layer "F.Cu")
		(at 198.41464 -69.804788 180)
		(property "Reference" "R3946"
			(at 0 0 180)
			(layer "F.SilkS")
			(hide yes)
			(effects
				(font
					(size 1.27 1.27)
				)
			)
		)
		(property "Value" ""
			(at 0 0 180)
			(layer "F.Fab")
			(effects
				(font
					(size 1.27 1.27)
				)
			)
		)
		(duplicate_pad_numbers_are_jumpers no)
		(fp_line
			(start 0.7874 0.4064)
			(end -0.7874 0.4064)
			(stroke
				(width 0.1524)
				(type default)
			)
			(layer "F.SilkS")
		)
		(fp_line
			(start 0.7874 -0.4064)
			(end 0.7874 0.4064)
			(stroke
				(width 0.1524)
				(type default)
			)
			(layer "F.SilkS")
		)
		(fp_line
			(start -0.7874 0.4064)
			(end -0.7874 -0.4064)
			(stroke
				(width 0.1524)
				(type default)
			)
			(layer "F.SilkS")
		)
		(fp_line
			(start -0.7874 -0.4064)
			(end 0.7874 -0.4064)
			(stroke
				(width 0.1524)
				(type default)
			)
			(layer "F.SilkS")
		)
		(fp_line
			(start 0.67945 0.3048)
			(end 0.120396 0.3048)
			(stroke
				(width 0.1)
				(type default)
			)
			(layer "F.Fab")
		)
		(fp_line
			(start 0.67945 -0.3048)
			(end 0.67945 0.3048)
			(stroke
				(width 0.1)
				(type default)
			)
			(layer "F.Fab")
		)
		(fp_line
			(start 0.12065 -0.2794)
			(end 0.12065 -0.3048)
			(stroke
				(width 0.1)
				(type default)
			)
			(layer "F.Fab")
		)
		(fp_line
			(start 0.12065 -0.3048)
			(end 0.67945 -0.3048)
			(stroke
				(width 0.1)
				(type default)
			)
			(layer "F.Fab")
		)
		(fp_line
			(start 0.120396 0.3048)
			(end 0.120396 0.2794)
			(stroke
				(width 0.1)
				(type default)
			)
			(layer "F.Fab")
		)
		(fp_line
			(start 0.120396 0.2794)
			(end -0.12065 0.2794)
			(stroke
				(width 0.1)
				(type default)
			)
			(layer "F.Fab")
		)
		(fp_line
			(start -0.12065 0.3048)
			(end -0.67945 0.3048)
			(stroke
				(width 0.1)
				(type default)
			)
			(layer "F.Fab")
		)
		(fp_line
			(start -0.12065 0.2794)
			(end -0.12065 0.3048)
			(stroke
				(width 0.1)
				(type default)
			)
			(layer "F.Fab")
		)
		(fp_line
			(start -0.12065 -0.2794)
			(end 0.12065 -0.2794)
			(stroke
				(width 0.1)
				(type default)
			)
			(layer "F.Fab")
		)
		(fp_line
			(start -0.12065 -0.305054)
			(end -0.12065 -0.2794)
			(stroke
				(width 0.1)
				(type default)
			)
			(layer "F.Fab")
		)
		(fp_line
			(start -0.67945 0.3048)
			(end -0.67945 -0.305054)
			(stroke
				(width 0.1)
				(type default)
			)
			(layer "F.Fab")
		)
		(fp_line
			(start -0.67945 -0.305054)
			(end -0.12065 -0.305054)
			(stroke
				(width 0.1)
				(type default)
			)
			(layer "F.Fab")
		)
		(pad "1" smd circle
			(at -0.40005 0 180)
			(size 0 0)
			(layers "F.Cu" "F.Mask" "F.Paste")
			(net "E1S_0_EN")
		)
		(pad "2" smd circle
			(at 0.40005 0 180)
			(size 0 0)
			(layers "F.Cu" "F.Mask" "F.Paste")
			(net "P3V3_E1S_EN_0_R2")
		)
	)
	(footprint ""
		(layer "F.Cu")
		(at 51.251358 -344.77325 -90)
		(property "Reference" "PL19"
			(at -2.028698 4.869688 90)
			(unlocked yes)
			(layer "F.SilkS")
			(effects
				(font
					(size 0.7874 0.5842)
					(thickness 0.1524)
				)
				(justify left)
			)
		)
		(property "Value" ""
			(at 0 0 270)
			(layer "F.Fab")
			(effects
				(font
					(size 1.27 1.27)
				)
			)
		)
		(duplicate_pad_numbers_are_jumpers no)
		(fp_line
			(start -4.99999 3.750056)
			(end -4.99999 2.2479)
			(stroke
				(width 0.1524)
				(type default)
			)
			(layer "F.SilkS")
		)
		(fp_line
			(start 0 3.750056)
			(end -4.99999 3.750056)
			(stroke
				(width 0.1524)
				(type default)
			)
			(layer "F.SilkS")
		)
		(fp_line
			(start 4.99999 3.750056)
			(end 0 3.750056)
			(stroke
				(width 0.1524)
				(type default)
			)
			(layer "F.SilkS")
		)
		(fp_line
			(start 4.99999 2.2352)
			(end 4.99999 3.750056)
			(stroke
				(width 0.1524)
				(type default)
			)
			(layer "F.SilkS")
		)
		(fp_line
			(start -4.99999 -2.2479)
			(end -4.99999 -3.750056)
			(stroke
				(width 0.1524)
				(type default)
			)
			(layer "F.SilkS")
		)
		(fp_line
			(start -4.99999 -3.750056)
			(end 4.99999 -3.750056)
			(stroke
				(width 0.1524)
				(type default)
			)
			(layer "F.SilkS")
		)
		(fp_line
			(start 4.99999 -3.750056)
			(end 4.99999 -2.2479)
			(stroke
				(width 0.1524)
				(type default)
			)
			(layer "F.SilkS")
		)
		(fp_line
			(start -4.99999 3.750056)
			(end -4.99999 -3.750056)
			(stroke
				(width 0.1)
				(type default)
			)
			(layer "F.Fab")
		)
		(fp_line
			(start 0 3.750056)
			(end -4.99999 3.750056)
			(stroke
				(width 0.1)
				(type default)
			)
			(layer "F.Fab")
		)
		(fp_line
			(start 4.99999 3.750056)
			(end 0 3.750056)
			(stroke
				(width 0.1)
				(type default)
			)
			(layer "F.Fab")
		)
		(fp_line
			(start -4.99999 -3.750056)
			(end 4.99999 -3.750056)
			(stroke
				(width 0.1)
				(type default)
			)
			(layer "F.Fab")
		)
		(fp_line
			(start 4.99999 -3.750056)
			(end 4.99999 3.750056)
			(stroke
				(width 0.1)
				(type default)
			)
			(layer "F.Fab")
		)
		(pad "1" smd rect
			(at -3.299968 0 270)
			(size 3.302 4.2164)
			(layers "F.Cu" "F.Mask" "F.Paste")
			(net "SW_PVCCFA_EHV_FIVRA_CPU1_SW2")
		)
		(pad "2" smd rect
			(at 3.299968 0 270)
			(size 3.302 4.2164)
			(layers "F.Cu" "F.Mask" "F.Paste")
			(net "PVCCFA_EHV_FIVRA_CPU1")
		)
	)
	(footprint ""
		(layer "F.Cu")
		(at 412.367984 -16.088614 90)
		(property "Reference" "C855"
			(at 0 0 90)
			(layer "F.SilkS")
			(hide yes)
			(effects
				(font
					(size 1.27 1.27)
				)
			)
		)
		(property "Value" ""
			(at 0 0 90)
			(layer "F.Fab")
			(effects
				(font
					(size 1.27 1.27)
				)
			)
		)
		(duplicate_pad_numbers_are_jumpers no)
		(fp_line
			(start 0.299974 -0.150114)
			(end 0.299974 0.150114)
			(stroke
				(width 0.1)
				(type default)
			)
			(layer "F.Fab")
		)
		(fp_line
			(start -0.299974 -0.150114)
			(end 0.299974 -0.150114)
			(stroke
				(width 0.1)
				(type default)
			)
			(layer "F.Fab")
		)
		(fp_line
			(start 0.299974 0.150114)
			(end -0.299974 0.150114)
			(stroke
				(width 0.1)
				(type default)
			)
			(layer "F.Fab")
		)
		(fp_line
			(start -0.299974 0.150114)
			(end -0.299974 -0.150114)
			(stroke
				(width 0.1)
				(type default)
			)
			(layer "F.Fab")
		)
		(pad "1" smd rect
			(at -0.2667 0 90)
			(size 0.3048 0.381)
			(layers "F.Cu" "F.Mask" "F.Paste")
			(net "P5E_CPU0_PE1_TX_C_DP<7>")
		)
		(pad "2" smd rect
			(at 0.2667 0 90)
			(size 0.3048 0.381)
			(layers "F.Cu" "F.Mask" "F.Paste")
			(net "P5E_CPU0_PE1_TX_DP<7>")
		)
	)
	(footprint ""
		(layer "F.Cu")
		(at 111.332772 -126.678182)
		(property "Reference" "R3535"
			(at 0 0 0)
			(layer "F.SilkS")
			(hide yes)
			(effects
				(font
					(size 1.27 1.27)
				)
			)
		)
		(property "Value" ""
			(at 0 0 0)
			(layer "F.Fab")
			(effects
				(font
					(size 1.27 1.27)
				)
			)
		)
		(duplicate_pad_numbers_are_jumpers no)
		(fp_line
			(start -0.7874 -0.4064)
			(end 0.7874 -0.4064)
			(stroke
				(width 0.1524)
				(type default)
			)
			(layer "F.SilkS")
		)
		(fp_line
			(start -0.7874 0.4064)
			(end -0.7874 -0.4064)
			(stroke
				(width 0.1524)
				(type default)
			)
			(layer "F.SilkS")
		)
		(fp_line
			(start 0.7874 -0.4064)
			(end 0.7874 0.4064)
			(stroke
				(width 0.1524)
				(type default)
			)
			(layer "F.SilkS")
		)
		(fp_line
			(start 0.7874 0.4064)
			(end -0.7874 0.4064)
			(stroke
				(width 0.1524)
				(type default)
			)
			(layer "F.SilkS")
		)
		(fp_line
			(start -0.67945 -0.305054)
			(end -0.12065 -0.305054)
			(stroke
				(width 0.1)
				(type default)
			)
			(layer "F.Fab")
		)
		(fp_line
			(start -0.67945 0.3048)
			(end -0.67945 -0.305054)
			(stroke
				(width 0.1)
				(type default)
			)
			(layer "F.Fab")
		)
		(fp_line
			(start -0.12065 -0.305054)
			(end -0.12065 -0.2794)
			(stroke
				(width 0.1)
				(type default)
			)
			(layer "F.Fab")
		)
		(fp_line
			(start -0.12065 -0.2794)
			(end 0.12065 -0.2794)
			(stroke
				(width 0.1)
				(type default)
			)
			(layer "F.Fab")
		)
		(fp_line
			(start -0.12065 0.2794)
			(end -0.12065 0.3048)
			(stroke
				(width 0.1)
				(type default)
			)
			(layer "F.Fab")
		)
		(fp_line
			(start -0.12065 0.3048)
			(end -0.67945 0.3048)
			(stroke
				(width 0.1)
				(type default)
			)
			(layer "F.Fab")
		)
		(fp_line
			(start 0.120396 0.2794)
			(end -0.12065 0.2794)
			(stroke
				(width 0.1)
				(type default)
			)
			(layer "F.Fab")
		)
		(fp_line
			(start 0.120396 0.3048)
			(end 0.120396 0.2794)
			(stroke
				(width 0.1)
				(type default)
			)
			(layer "F.Fab")
		)
		(fp_line
			(start 0.12065 -0.3048)
			(end 0.67945 -0.3048)
			(stroke
				(width 0.1)
				(type default)
			)
			(layer "F.Fab")
		)
		(fp_line
			(start 0.12065 -0.2794)
			(end 0.12065 -0.3048)
			(stroke
				(width 0.1)
				(type default)
			)
			(layer "F.Fab")
		)
		(fp_line
			(start 0.67945 -0.3048)
			(end 0.67945 0.3048)
			(stroke
				(width 0.1)
				(type default)
			)
			(layer "F.Fab")
		)
		(fp_line
			(start 0.67945 0.3048)
			(end 0.120396 0.3048)
			(stroke
				(width 0.1)
				(type default)
			)
			(layer "F.Fab")
		)
		(pad "1" smd circle
			(at -0.40005 0)
			(size 0 0)
			(layers "F.Cu" "F.Mask" "F.Paste")
			(net "P3V3_AUX")
		)
		(pad "2" smd circle
			(at 0.40005 0)
			(size 0 0)
			(layers "F.Cu" "F.Mask" "F.Paste")
			(net "SMB_SENSOR_E1S_3V3AUX_SCL")
		)
	)
	(footprint ""
		(layer "F.Cu")
		(at 406.124664 -364.151926)
		(property "Reference" "R515"
			(at 0 0 0)
			(layer "F.SilkS")
			(hide yes)
			(effects
				(font
					(size 1.27 1.27)
				)
			)
		)
		(property "Value" ""
			(at 0 0 0)
			(layer "F.Fab")
			(effects
				(font
					(size 1.27 1.27)
				)
			)
		)
		(duplicate_pad_numbers_are_jumpers no)
		(fp_line
			(start -0.7874 -0.4064)
			(end 0.7874 -0.4064)
			(stroke
				(width 0.1524)
				(type default)
			)
			(layer "F.SilkS")
		)
		(fp_line
			(start -0.7874 0.4064)
			(end -0.7874 -0.4064)
			(stroke
				(width 0.1524)
				(type default)
			)
			(layer "F.SilkS")
		)
		(fp_line
			(start 0.7874 -0.4064)
			(end 0.7874 0.4064)
			(stroke
				(width 0.1524)
				(type default)
			)
			(layer "F.SilkS")
		)
		(fp_line
			(start 0.7874 0.4064)
			(end -0.7874 0.4064)
			(stroke
				(width 0.1524)
				(type default)
			)
			(layer "F.SilkS")
		)
		(fp_line
			(start -0.67945 -0.305054)
			(end -0.12065 -0.305054)
			(stroke
				(width 0.1)
				(type default)
			)
			(layer "F.Fab")
		)
		(fp_line
			(start -0.67945 0.3048)
			(end -0.67945 -0.305054)
			(stroke
				(width 0.1)
				(type default)
			)
			(layer "F.Fab")
		)
		(fp_line
			(start -0.12065 -0.305054)
			(end -0.12065 -0.2794)
			(stroke
				(width 0.1)
				(type default)
			)
			(layer "F.Fab")
		)
		(fp_line
			(start -0.12065 -0.2794)
			(end 0.12065 -0.2794)
			(stroke
				(width 0.1)
				(type default)
			)
			(layer "F.Fab")
		)
		(fp_line
			(start -0.12065 0.2794)
			(end -0.12065 0.3048)
			(stroke
				(width 0.1)
				(type default)
			)
			(layer "F.Fab")
		)
		(fp_line
			(start -0.12065 0.3048)
			(end -0.67945 0.3048)
			(stroke
				(width 0.1)
				(type default)
			)
			(layer "F.Fab")
		)
		(fp_line
			(start 0.120396 0.2794)
			(end -0.12065 0.2794)
			(stroke
				(width 0.1)
				(type default)
			)
			(layer "F.Fab")
		)
		(fp_line
			(start 0.120396 0.3048)
			(end 0.120396 0.2794)
			(stroke
				(width 0.1)
				(type default)
			)
			(layer "F.Fab")
		)
		(fp_line
			(start 0.12065 -0.3048)
			(end 0.67945 -0.3048)
			(stroke
				(width 0.1)
				(type default)
			)
			(layer "F.Fab")
		)
		(fp_line
			(start 0.12065 -0.2794)
			(end 0.12065 -0.3048)
			(stroke
				(width 0.1)
				(type default)
			)
			(layer "F.Fab")
		)
		(fp_line
			(start 0.67945 -0.3048)
			(end 0.67945 0.3048)
			(stroke
				(width 0.1)
				(type default)
			)
			(layer "F.Fab")
		)
		(fp_line
			(start 0.67945 0.3048)
			(end 0.120396 0.3048)
			(stroke
				(width 0.1)
				(type default)
			)
			(layer "F.Fab")
		)
		(pad "1" smd circle
			(at -0.40005 0)
			(size 0 0)
			(layers "F.Cu" "F.Mask" "F.Paste")
			(net "PD_PIROM_CPU0_ADDR0")
		)
		(pad "2" smd circle
			(at 0.40005 0)
			(size 0 0)
			(layers "F.Cu" "F.Mask" "F.Paste")
			(net "GND")
		)
	)
)
